# BASEBOARD_FAB2 (Tioga Pass) — schematic netlist excerpt (pin names and nets, part order shuffled) for the footprints in the layout excerpt that follows; sources: Cadence DE-HDL packaged netlist, KiCad conversion of Wiwynn_Tioga_Pass_MB.brd

R25W5  120R2F-GP  1%  pkg RCL_GP  page 151 : \1\ = GND ; \2\ = BMC_M_CS_N
C12W1  CAP  47.0PF 50V 5% COG  pkg 0402LF  page 197 : A = VR_PVDDQ_ABC_AIINSEN ; B = VR_PVDDQ_ABC_VINSEN
R9E19  RES  22.1 1.0% CHIP  pkg 0402  page 139 : A = RMII_SPRNGVLLE_BMC_PCH_RXD1_R ; B = RMII_SPRNGVLLE_BMC_PCH_RXD1

(kicad_pcb
	(version 20260206)
	(generator "pcbnew")
	(generator_version "10.0")
	(general
		(thickness 1.6)
		(legacy_teardrops no)
	)
	(paper "A4")
	(title_block
		(title "Wiwynn_Tioga_Pass_MB.brd")
		(comment 1 "Tioga Pass / footprints 83-85 of 4770")
	)
	(layers
		(0 "F.Cu" signal "TOP")
		(4 "In1.Cu" signal "L2GND")
		(6 "In2.Cu" signal "L3")
		(8 "In3.Cu" signal "L4GND")
		(10 "In4.Cu" signal "L5")
		(12 "In5.Cu" signal "L6GND")
		(14 "In6.Cu" signal "L7VCC")
		(16 "In7.Cu" signal "L8VCC")
		(18 "In8.Cu" signal "L9GND")
		(20 "In9.Cu" signal "L10")
		(22 "In10.Cu" signal "L11GND")
		(24 "In11.Cu" signal "L12")
		(26 "In12.Cu" signal "L13GND")
		(2 "B.Cu" signal "BOTTOM")
		(9 "F.Adhes" user "F.Adhesive")
		(11 "B.Adhes" user "B.Adhesive")
		(13 "F.Paste" user "Package Geometry/Pastemask Top")
		(15 "B.Paste" user "Package Geometry/Pastemask Bottom")
		(5 "F.SilkS" user "Ref Des/Silkscreen Top")
		(7 "B.SilkS" user "Ref Des/Silkscreen Bottom")
		(1 "F.Mask" user "Board Geometry/Soldermask Top")
		(3 "B.Mask" user "Board Geometry/Soldermask Bottom")
		(17 "Dwgs.User" user "User.Drawings")
		(19 "Cmts.User" user "User.Comments")
		(21 "Eco1.User" user "User.Eco1")
		(23 "Eco2.User" user "User.Eco2")
		(25 "Edge.Cuts" user "Board Geometry/Outline")
		(27 "Margin" user)
		(31 "F.CrtYd" user "Package Geometry/Place Bound Top")
		(29 "B.CrtYd" user "Package Geometry/Place Bound Bottom")
		(35 "F.Fab" user "Ref Des/Assembly Top")
		(33 "B.Fab" user "Ref Des/Assembly Bottom")
	)
	(footprint ""
		(layer "F.Cu")
		(at 441.119006 -41.663874 180)
		(property "Reference" "R25W5"
			(at 0 0 180)
			(layer "F.SilkS")
			(hide yes)
			(effects
				(font
					(size 1.27 1.27)
				)
			)
		)
		(property "Value" "*"
			(at 0.064008 -4.108196 180)
			(unlocked yes)
			(layer "F.Fab")
			(hide yes)
			(effects
				(font
					(size 1.27 1.016)
					(thickness 0.1524)
				)
			)
		)
		(property "Device Type" "120R2F-GP_RCL_GP-120R2F-GP,64.A"
			(at 0.064008 -5.632196 180)
			(unlocked yes)
			(layer "F.Fab")
			(hide yes)
			(effects
				(font
					(size 1.27 1.016)
					(thickness 0.1524)
				)
			)
		)
		(duplicate_pad_numbers_are_jumpers no)
		(fp_line
			(start 0.508 -0.9398)
			(end -0.508 -0.9398)
			(stroke
				(width 0.1524)
				(type default)
			)
			(layer "F.SilkS")
		)
		(fp_line
			(start -0.508 -0.9398)
			(end -0.508 0.9398)
			(stroke
				(width 0.1524)
				(type default)
			)
			(layer "F.SilkS")
		)
		(fp_rect
			(start -0.508 0.9398)
			(end 0.508 -0.9398)
			(stroke
				(width 0)
				(type default)
			)
			(fill no)
			(layer "F.CrtYd")
		)
		(fp_rect
			(start -0.508 0.9398)
			(end 0.508 -0.9398)
			(stroke
				(width 0)
				(type default)
			)
			(fill no)
			(layer "F.Fab")
		)
		(pad "1" smd custom
			(at 0 -0.4445 180)
			(size 0.1397 0.1397)
			(layers "F.Cu" "F.Mask" "F.Paste")
			(net "GND")
			(options
				(clearance outline)
				(anchor circle)
			)
			(primitives
				(gr_poly
					(pts
						(arc
							(start -0.1778 -0.2794)
							(mid -0.249642 -0.249642)
							(end -0.2794 -0.1778)
						)
						(arc
							(start -0.2794 0.1778)
							(mid -0.249642 0.249642)
							(end -0.1778 0.2794)
						)
						(arc
							(start 0.1778 0.2794)
							(mid 0.249642 0.249642)
							(end 0.2794 0.1778)
						)
						(arc
							(start 0.2794 -0.1778)
							(mid 0.249642 -0.249642)
							(end 0.1778 -0.2794)
						)
					)
					(width 0)
					(fill yes)
				)
			)
		)
		(pad "2" smd custom
			(at 0 0.4445 180)
			(size 0.1397 0.1397)
			(layers "F.Cu" "F.Mask" "F.Paste")
			(net "BMC_M_CS_N")
			(options
				(clearance outline)
				(anchor circle)
			)
			(primitives
				(gr_poly
					(pts
						(arc
							(start -0.1778 -0.2794)
							(mid -0.249642 -0.249642)
							(end -0.2794 -0.1778)
						)
						(arc
							(start -0.2794 0.1778)
							(mid -0.249642 0.249642)
							(end -0.1778 0.2794)
						)
						(arc
							(start 0.1778 0.2794)
							(mid 0.249642 0.249642)
							(end 0.2794 0.1778)
						)
						(arc
							(start 0.2794 -0.1778)
							(mid 0.249642 -0.249642)
							(end 0.1778 -0.2794)
						)
					)
					(width 0)
					(fill yes)
				)
			)
		)
	)
	(footprint ""
		(layer "F.Cu")
		(at 491.0455 -42.0624 90)
		(property "Reference" "R9E19"
			(at 0 0 90)
			(layer "F.SilkS")
			(hide yes)
			(effects
				(font
					(size 1.27 1.27)
				)
			)
		)
		(property "Value" ""
			(at 0 0 90)
			(layer "F.Fab")
			(effects
				(font
					(size 1.27 1.27)
				)
			)
		)
		(duplicate_pad_numbers_are_jumpers no)
		(fp_poly
			(pts
				(xy -0.2794 -0.1016) (xy 0.2794 -0.1016) (xy 0.2794 0.9906) (xy -0.2794 0.9906)
			)
			(stroke
				(width 0)
				(type default)
			)
			(fill no)
			(layer "F.CrtYd")
		)
		(fp_line
			(start 0.2794 -0.1016)
			(end -0.2794 -0.1016)
			(stroke
				(width 0.1)
				(type default)
			)
			(layer "F.Fab")
		)
		(fp_line
			(start -0.2794 -0.1016)
			(end -0.2794 0.9906)
			(stroke
				(width 0.1)
				(type default)
			)
			(layer "F.Fab")
		)
		(fp_line
			(start 0.2794 0.9906)
			(end 0.2794 -0.1016)
			(stroke
				(width 0.1)
				(type default)
			)
			(layer "F.Fab")
		)
		(fp_line
			(start -0.2794 0.9906)
			(end 0.2794 0.9906)
			(stroke
				(width 0.1)
				(type default)
			)
			(layer "F.Fab")
		)
		(pad "1" smd rect
			(at 0 0 90)
			(size 0.508 0.508)
			(layers "F.Cu" "F.Mask" "F.Paste")
			(net "RMII_SPRNGVLLE_BMC_PCH_RXD1_R")
		)
		(pad "2" smd rect
			(at 0 0.889 90)
			(size 0.508 0.508)
			(layers "F.Cu" "F.Mask" "F.Paste")
			(net "RMII_SPRNGVLLE_BMC_PCH_RXD1")
		)
		(zone
			(layer "F.Cu")
			(hatch none 0.5)
			(connect_pads
				(clearance 0)
			)
			(min_thickness 0.25)
			(keepout
				(tracks allowed)
				(vias not_allowed)
				(pads allowed)
				(copperpour not_allowed)
				(footprints allowed)
			)
			(placement
				(enabled no)
				(sheetname "")
			)
			(fill
				(thermal_gap 0.5)
				(thermal_bridge_width 0.5)
				(island_removal_mode 0)
			)
			(polygon
				(pts
					(xy 491.2995 -41.8084) (xy 491.2995 -42.3164) (xy 491.6805 -42.3164) (xy 491.6805 -41.8084)
				)
			)
		)
		(zone
			(layer "F.Cu")
			(hatch none 0.5)
			(connect_pads
				(clearance 0)
			)
			(min_thickness 0.25)
			(keepout
				(tracks not_allowed)
				(vias allowed)
				(pads allowed)
				(copperpour not_allowed)
				(footprints allowed)
			)
			(placement
				(enabled no)
				(sheetname "")
			)
			(fill
				(thermal_gap 0.5)
				(thermal_bridge_width 0.5)
				(island_removal_mode 0)
			)
			(polygon
				(pts
					(xy 491.6805 -41.8084) (xy 491.6805 -42.3164) (xy 491.2995 -42.3164) (xy 491.2995 -41.8084)
				)
			)
		)
	)
	(footprint ""
		(layer "F.Cu")
		(at 349.040958 -16.632428)
		(property "Reference" "C12W1"
			(at -0.8382 -0.67818 0)
			(unlocked yes)
			(layer "F.SilkS")
			(effects
				(font
					(size 0.4064 0.254)
					(thickness 0.1524)
				)
				(justify left)
			)
		)
		(property "Value" ""
			(at 0 0 0)
			(layer "F.Fab")
			(effects
				(font
					(size 1.27 1.27)
				)
			)
		)
		(duplicate_pad_numbers_are_jumpers no)
		(fp_poly
			(pts
				(xy 0.3048 -0.1016) (xy 0.3048 0.9906) (xy -0.3048 0.9906) (xy -0.3048 -0.1016)
			)
			(stroke
				(width 0)
				(type default)
			)
			(fill no)
			(layer "F.CrtYd")
		)
		(fp_line
			(start -0.3048 -0.1016)
			(end -0.3048 0.9906)
			(stroke
				(width 0.1)
				(type default)
			)
			(layer "F.Fab")
		)
		(fp_line
			(start -0.3048 0.9906)
			(end 0.3048 0.9906)
			(stroke
				(width 0.1)
				(type default)
			)
			(layer "F.Fab")
		)
		(fp_line
			(start 0.3048 -0.1016)
			(end -0.3048 -0.1016)
			(stroke
				(width 0.1)
				(type default)
			)
			(layer "F.Fab")
		)
		(fp_line
			(start 0.3048 0.9906)
			(end 0.3048 -0.1016)
			(stroke
				(width 0.1)
				(type default)
			)
			(layer "F.Fab")
		)
		(pad "1" smd rect
			(at 0 0)
			(size 0.508 0.508)
			(layers "F.Cu" "F.Mask" "F.Paste")
			(net "VR_PVDDQ_ABC_AIINSEN")
		)
		(pad "2" smd rect
			(at 0 0.889)
			(size 0.508 0.508)
			(layers "F.Cu" "F.Mask" "F.Paste")
			(net "VR_PVDDQ_ABC_VINSEN")
		)
		(zone
			(layer "F.Cu")
			(hatch none 0.5)
			(connect_pads
				(clearance 0)
			)
			(min_thickness 0.25)
			(keepout
				(tracks allowed)
				(vias not_allowed)
				(pads allowed)
				(copperpour not_allowed)
				(footprints allowed)
			)
			(placement
				(enabled no)
				(sheetname "")
			)
			(fill
				(thermal_gap 0.5)
				(thermal_bridge_width 0.5)
				(island_removal_mode 0)
			)
			(polygon
				(pts
					(xy 348.786958 -16.378428) (xy 349.294958 -16.378428) (xy 349.294958 -15.997428) (xy 348.786958 -15.997428)
				)
			)
		)
		(zone
			(layer "F.Cu")
			(hatch none 0.5)
			(connect_pads
				(clearance 0)
			)
			(min_thickness 0.25)
			(keepout
				(tracks not_allowed)
				(vias allowed)
				(pads allowed)
				(copperpour not_allowed)
				(footprints allowed)
			)
			(placement
				(enabled no)
				(sheetname "")
			)
			(fill
				(thermal_gap 0.5)
				(thermal_bridge_width 0.5)
				(island_removal_mode 0)
			)
			(polygon
				(pts
					(xy 348.786958 -15.997428) (xy 349.294958 -15.997428) (xy 349.294958 -16.378428) (xy 348.786958 -16.378428)
				)
			)
		)
	)
)
